# SCM (Grand Teton) — schematic netlist excerpt (pin names and nets, part order shuffled) for the footprints in the layout excerpt that follows; sources: Cadence DE-HDL packaged netlist, KiCad conversion of 12092022_DA0F0TMDCD0_F0T_Management_Board_D_brd_V3_OCP.brd

R102  Q_RES  33.2 1% CHIP  pkg 0402LF  page 30 : A = UART_BMC_5_TXD_BUF ; B = UART_BMC_5_TXD_BUF_R
R85  Q_RES  0 5% CHIP  pkg 0402LF  page 23 : A = V_VGAHS_BUF_R ; B = V_VGAHS_BUF

(kicad_pcb
	(version 20260206)
	(generator "pcbnew")
	(generator_version "10.0")
	(general
		(thickness 1.6)
		(legacy_teardrops no)
	)
	(paper "A4")
	(title_block
		(title "12092022_DA0F0TMDCD0_F0T_Management_Board_D_brd_V3_OCP.brd")
		(comment 1 "Grand Teton / footprints 1295-1296 of 1440")
	)
	(layers
		(0 "F.Cu" signal "TOP")
		(4 "In1.Cu" signal "GND")
		(6 "In2.Cu" signal "IN1")
		(8 "In3.Cu" signal "GND1")
		(10 "In4.Cu" signal "IN2")
		(12 "In5.Cu" signal "VCC")
		(14 "In6.Cu" signal "VCC1")
		(16 "In7.Cu" signal "IN3")
		(18 "In8.Cu" signal "GND2")
		(20 "In9.Cu" signal "IN4")
		(22 "In10.Cu" signal "GND3")
		(2 "B.Cu" signal "BOTTOM")
		(9 "F.Adhes" user "F.Adhesive")
		(11 "B.Adhes" user "B.Adhesive")
		(13 "F.Paste" user "Package Geometry/Pastemask Top")
		(15 "B.Paste" user "Package Geometry/Pastemask Bottom")
		(5 "F.SilkS" user "Ref Des/Silkscreen Top")
		(7 "B.SilkS" user "Ref Des/Silkscreen Bottom")
		(1 "F.Mask" user "Board Geometry/Soldermask Top")
		(3 "B.Mask" user "Board Geometry/Soldermask Bottom")
		(17 "Dwgs.User" user "User.Drawings")
		(19 "Cmts.User" user "User.Comments")
		(21 "Eco1.User" user "User.Eco1")
		(23 "Eco2.User" user "User.Eco2")
		(25 "Edge.Cuts" user "Board Geometry/Outline")
		(27 "Margin" user)
		(31 "F.CrtYd" user "Package Geometry/Place Bound Top")
		(29 "B.CrtYd" user "Package Geometry/Place Bound Bottom")
		(35 "F.Fab" user "Ref Des/Assembly Top")
		(33 "B.Fab" user "Ref Des/Assembly Bottom")
	)
	(footprint ""
		(layer "B.Cu")
		(at 4.2672 -28.1686 -90)
		(property "Reference" "R102"
			(at 0 0 90)
			(layer "B.SilkS")
			(hide yes)
			(effects
				(font
					(size 1.27 1.27)
				)
				(justify mirror)
			)
		)
		(property "Value" ""
			(at 0 0 90)
			(layer "B.Fab")
			(effects
				(font
					(size 1.27 1.27)
				)
				(justify mirror)
			)
		)
		(duplicate_pad_numbers_are_jumpers no)
		(fp_line
			(start -0.7874 0.4064)
			(end 0.7874 0.4064)
			(stroke
				(width 0.1524)
				(type default)
			)
			(layer "B.SilkS")
		)
		(fp_line
			(start 0.7874 0.4064)
			(end 0.7874 -0.4064)
			(stroke
				(width 0.1524)
				(type default)
			)
			(layer "B.SilkS")
		)
		(fp_line
			(start -0.7874 -0.4064)
			(end -0.7874 0.4064)
			(stroke
				(width 0.1524)
				(type default)
			)
			(layer "B.SilkS")
		)
		(fp_line
			(start 0.7874 -0.4064)
			(end -0.7874 -0.4064)
			(stroke
				(width 0.1524)
				(type default)
			)
			(layer "B.SilkS")
		)
		(fp_line
			(start -0.67945 0.3048)
			(end -0.120396 0.3048)
			(stroke
				(width 0.1)
				(type default)
			)
			(layer "B.Fab")
		)
		(fp_line
			(start -0.120396 0.3048)
			(end -0.120396 0.2794)
			(stroke
				(width 0.1)
				(type default)
			)
			(layer "B.Fab")
		)
		(fp_line
			(start 0.12065 0.3048)
			(end 0.67945 0.3048)
			(stroke
				(width 0.1)
				(type default)
			)
			(layer "B.Fab")
		)
		(fp_line
			(start 0.67945 0.3048)
			(end 0.67945 -0.305054)
			(stroke
				(width 0.1)
				(type default)
			)
			(layer "B.Fab")
		)
		(fp_line
			(start -0.120396 0.2794)
			(end 0.12065 0.2794)
			(stroke
				(width 0.1)
				(type default)
			)
			(layer "B.Fab")
		)
		(fp_line
			(start 0.12065 0.2794)
			(end 0.12065 0.3048)
			(stroke
				(width 0.1)
				(type default)
			)
			(layer "B.Fab")
		)
		(fp_line
			(start -0.12065 -0.2794)
			(end -0.12065 -0.3048)
			(stroke
				(width 0.1)
				(type default)
			)
			(layer "B.Fab")
		)
		(fp_line
			(start 0.12065 -0.2794)
			(end -0.12065 -0.2794)
			(stroke
				(width 0.1)
				(type default)
			)
			(layer "B.Fab")
		)
		(fp_line
			(start -0.67945 -0.3048)
			(end -0.67945 0.3048)
			(stroke
				(width 0.1)
				(type default)
			)
			(layer "B.Fab")
		)
		(fp_line
			(start -0.12065 -0.3048)
			(end -0.67945 -0.3048)
			(stroke
				(width 0.1)
				(type default)
			)
			(layer "B.Fab")
		)
		(fp_line
			(start 0.12065 -0.305054)
			(end 0.12065 -0.2794)
			(stroke
				(width 0.1)
				(type default)
			)
			(layer "B.Fab")
		)
		(fp_line
			(start 0.67945 -0.305054)
			(end 0.12065 -0.305054)
			(stroke
				(width 0.1)
				(type default)
			)
			(layer "B.Fab")
		)
		(pad "1" smd circle
			(at 0.40005 0 90)
			(size 0 0)
			(layers "B.Cu" "B.Mask" "B.Paste")
			(net "UART_BMC_5_TXD_BUF")
		)
		(pad "2" smd circle
			(at -0.40005 0 90)
			(size 0 0)
			(layers "B.Cu" "B.Mask" "B.Paste")
			(net "UART_BMC_5_TXD_BUF_R")
		)
	)
	(footprint ""
		(layer "B.Cu")
		(at 39.497 -6.731 -90)
		(property "Reference" "R85"
			(at 0 0 90)
			(layer "B.SilkS")
			(hide yes)
			(effects
				(font
					(size 1.27 1.27)
				)
				(justify mirror)
			)
		)
		(property "Value" ""
			(at 0 0 90)
			(layer "B.Fab")
			(effects
				(font
					(size 1.27 1.27)
				)
				(justify mirror)
			)
		)
		(duplicate_pad_numbers_are_jumpers no)
		(fp_line
			(start -0.7874 0.4064)
			(end 0.7874 0.4064)
			(stroke
				(width 0.1524)
				(type default)
			)
			(layer "B.SilkS")
		)
		(fp_line
			(start 0.7874 0.4064)
			(end 0.7874 -0.4064)
			(stroke
				(width 0.1524)
				(type default)
			)
			(layer "B.SilkS")
		)
		(fp_line
			(start -0.7874 -0.4064)
			(end -0.7874 0.4064)
			(stroke
				(width 0.1524)
				(type default)
			)
			(layer "B.SilkS")
		)
		(fp_line
			(start 0.7874 -0.4064)
			(end -0.7874 -0.4064)
			(stroke
				(width 0.1524)
				(type default)
			)
			(layer "B.SilkS")
		)
		(fp_line
			(start -0.67945 0.3048)
			(end -0.120396 0.3048)
			(stroke
				(width 0.1)
				(type default)
			)
			(layer "B.Fab")
		)
		(fp_line
			(start -0.120396 0.3048)
			(end -0.120396 0.2794)
			(stroke
				(width 0.1)
				(type default)
			)
			(layer "B.Fab")
		)
		(fp_line
			(start 0.12065 0.3048)
			(end 0.67945 0.3048)
			(stroke
				(width 0.1)
				(type default)
			)
			(layer "B.Fab")
		)
		(fp_line
			(start 0.67945 0.3048)
			(end 0.67945 -0.305054)
			(stroke
				(width 0.1)
				(type default)
			)
			(layer "B.Fab")
		)
		(fp_line
			(start -0.120396 0.2794)
			(end 0.12065 0.2794)
			(stroke
				(width 0.1)
				(type default)
			)
			(layer "B.Fab")
		)
		(fp_line
			(start 0.12065 0.2794)
			(end 0.12065 0.3048)
			(stroke
				(width 0.1)
				(type default)
			)
			(layer "B.Fab")
		)
		(fp_line
			(start -0.12065 -0.2794)
			(end -0.12065 -0.3048)
			(stroke
				(width 0.1)
				(type default)
			)
			(layer "B.Fab")
		)
		(fp_line
			(start 0.12065 -0.2794)
			(end -0.12065 -0.2794)
			(stroke
				(width 0.1)
				(type default)
			)
			(layer "B.Fab")
		)
		(fp_line
			(start -0.67945 -0.3048)
			(end -0.67945 0.3048)
			(stroke
				(width 0.1)
				(type default)
			)
			(layer "B.Fab")
		)
		(fp_line
			(start -0.12065 -0.3048)
			(end -0.67945 -0.3048)
			(stroke
				(width 0.1)
				(type default)
			)
			(layer "B.Fab")
		)
		(fp_line
			(start 0.12065 -0.305054)
			(end 0.12065 -0.2794)
			(stroke
				(width 0.1)
				(type default)
			)
			(layer "B.Fab")
		)
		(fp_line
			(start 0.67945 -0.305054)
			(end 0.12065 -0.305054)
			(stroke
				(width 0.1)
				(type default)
			)
			(layer "B.Fab")
		)
		(pad "1" smd circle
			(at 0.40005 0 90)
			(size 0 0)
			(layers "B.Cu" "B.Mask" "B.Paste")
			(net "V_VGAHS_BUF_R")
		)
		(pad "2" smd circle
			(at -0.40005 0 90)
			(size 0 0)
			(layers "B.Cu" "B.Mask" "B.Paste")
			(net "V_VGAHS_BUF")
		)
	)
)
